# BASEBOARD_FAB2 (Tioga Pass) — schematic parts with pin connectivity, parts 4665–4665 of 4751; source: Cadence DE-HDL packaged netlist (pstxprt.dat, pstxnet.dat, pstchip.dat)

U5D1  SKX_EXT_B  IC  pkg BGA1  page 21  (pins 1696-2034 of 3647)
  CR30  PE3_RBIAS(1)  IN  = A_CPU0_PE3_RBIAS
  CR32  VSS(387)  GROUND  = GND
  CR34  VCCIN(18)  POWER  = PVCCIN_CPU0
  CR54  VCCIN(17)  POWER  = PVCCIN_CPU0
  CR56  VCCIN(16)  POWER  = PVCCIN_CPU0
  CR58  VSS(386)  GROUND  = GND
  CR60  RSVD(72)  BI  = TP_CPU0_RSVD_72
  CR62  VSS(385)  GROUND  = GND
  CR64  VSS(384)  GROUND  = GND
  CR66  VSS(383)  GROUND  = GND
  CR68  VSS(382)  GROUND  = GND
  CR74  DDR5_DQ(0)  BI  = M_F_DQ<0>
  CR76  DDR5_DQS_DP(0)  BI  = M_F_DQS_DP<0>
  CR78  VSS(381)  GROUND  = GND
  CR80  DDR4_DQ(6)  BI  = M_E_DQ<6>
  CR82  DDR4_DQ(3)  BI  = M_E_DQ<3>
  CR84  DDR3_DQS_DN(9)  BI  = M_D_DQS_DN<9>
  CR86  VSS(380)  GROUND  = GND
  CT1  PE2_TX_DN(2)  OUT  = P3E_CPU0_PE2_SS_TXN<2>
  CT3  PE2_TX_DN(3)  OUT  = P3E_CPU0_PE2_SS_TXN<3>
  CT5  RSVD(70)  BI  = TP_CPU0_RSVD_70
  CT7  VSS(1063)  GROUND  = GND
  CT9  PE2_RX_DN(0)  IN  = P3E_CPU0_PE2_SS_RXN<0>
  CT11  DMI_RX_DN(3)  IN  = DMI_CPU0_PCH_RX_C_DN<3>
  CT13  VSS(378)  GROUND  = GND
  CT19  VSS(377)  GROUND  = GND
  CT21  UPI2_RX_DN(8)  IN  = GND
  CT23  RSVD(71)  BI  = PVCCMCP_CPU0
  CT25  BCLK2_DN  IN  = CLK_100M_CPU0_BCLK2_DN
  CT27  VSS(376)  GROUND  = GND
  CT29  VSS(375)  GROUND  = GND
  CT31  MCP01_RBIAS(1)  BI  = A_CPU0_MCP01_RBIAS
  CT33  VSS(374)  GROUND  = GND
  CT35  VSS(373)  GROUND  = GND
  CT37  VCCIN(15)  POWER  = PVCCIN_CPU0
  CT39  VCCIN(14)  POWER  = PVCCIN_CPU0
  CT41  VCCIN(13)  POWER  = PVCCIN_CPU0
  CT53  VCCIN(12)  POWER  = PVCCIN_CPU0
  CT55  VCCIN(11)  POWER  = PVCCIN_CPU0
  CT57  VSS(372)  GROUND  = GND
  CT59  SMBCLK  BI  = SMB_PIROM_CPU0_SCL
  CT61  DDR4_CAVREF  OUT  = M_E_CPU_VREF
  CT63  DDR5_DQ(27)  BI  = M_F_DQ<27>
  CT65  DDR5_DQS_DP(3)  BI  = M_F_DQS_DP<3>
  CT67  DDR5_DQ(29)  BI  = M_F_DQ<29>
  CT69  RSVD(69)  BI  = TP_CPU0_RSVD_69
  CT73  VSS(371)  GROUND  = GND
  CT75  DDR5_DQS_DN(9)  BI  = M_F_DQS_DN<9>
  CT77  DDR5_DQ(7)  BI  = M_F_DQ<7>
  CT79  VSS(370)  GROUND  = GND
  CT81  DDR4_DQ(2)  BI  = M_E_DQ<2>
  CT83  VSS(369)  GROUND  = GND
  CT85  VSS(368)  GROUND  = GND
  CU2  PE2_TX_DP(1)  OUT  = P3E_CPU0_PE2_SS_TXP<1>
  CU4  VSS(367)  GROUND  = GND
  CU6  RSVD(67)  BI  = TP_CPU0_RSVD_67
  CU8  PE1_RX_DP(0)  IN  = P3E_CPU0_PE1_SS_RXP<0>
  CU10  PE3_RX_DP(15)  IN  = P3E_CPU0_PE3_OCP_RXP<15>
  CU12  VCCIO(18)  POWER  = PVCCIO_CPU0
  CU14  UPI2_TX_DN(12)  OUT  = TP_CPU0_UPI2_RSVD_DD17
  CU18  VCCIO(16)  POWER  = PVCCIO_CPU0
  CU20  UPI2_RX_DP(6)  IN  = GND
  CU22  VSS(366)  GROUND  = GND
  CU24  RSVD(68)  BI  = PVCCMCP_CPU0
  CU26  BCLK2_DP  IN  = CLK_100M_CPU0_BCLK2_DP
  CU28  VSS(365)  GROUND  = GND
  CU30  VSS(364)  GROUND  = GND
  CU32  MCP01_RBIAS(0)  BI  = A_CPU0_MCP01_RBIAS
  CU34  VSS(363)  GROUND  = GND
  CU36  VSS(362)  GROUND  = GND
  CU38  VCCIN(10)  POWER  = PVCCIN_CPU0
  CU40  VCCIN(9)  POWER  = PVCCIN_CPU0
  CU42  VCCIN(8)  POWER  = PVCCIN_CPU0
  CU52  VCCIN(7)  POWER  = PVCCIN_CPU0
  CU54  VCCIN(6)  POWER  = PVCCIN_CPU0
  CU56  VSS(361)  GROUND  = GND
  CU58  PIROM_ADDR(0)  BI  = PD_PIROM_CPU0_ADDR0
  CU60  RSVD(66)  BI  = TP_CPU0_RSVD_66
  CU62  VSS(360)  GROUND  = GND
  CU64  DDR5_DQ(31)  BI  = M_F_DQ<31>
  CU66  DDR5_DQ(25)  BI  = M_F_DQ<25>
  CU68  VSS(359)  GROUND  = GND
  CU74  DDR5_DQS_DP(9)  BI  = M_F_DQS_DP<9>
  CU76  VSS(358)  GROUND  = GND
  CU78  VSS(357)  GROUND  = GND
  CU80  VSS(356)  GROUND  = GND
  CU82  VSS(355)  GROUND  = GND
  CU84  DDR3_DQS_DN(0)  BI  = M_D_DQS_DN<0>
  CU86  VSS(354)  GROUND  = GND
  CV1  VSS(353)  GROUND  = GND
  CV3  PE2_TX_DN(1)  OUT  = P3E_CPU0_PE2_SS_TXN<1>
  CV5  PE3_TX_DP(15)  OUT  = P3E_CPU0_PE3_OCP_TXP<15>
  CV7  VCCIO(23)  POWER  = PVCCIO_CPU0
  CV9  PE3_RX_DN(15)  IN  = P3E_CPU0_PE3_OCP_RXN<15>
  CV11  DMI_RX_DP(3)  IN  = DMI_CPU0_PCH_RX_C_DP<3>
  CV13  UPI2_TX_DP(11)  OUT  = TP_CPU0_UPI2_RSVD_DD15
  CV17  VSS(351)  GROUND  = GND
  CV19  UPI2_RX_DN(7)  IN  = GND
  CV21  VCCIO(17)  POWER  = PVCCIO_CPU0
  CV23  RSVD(65)  BI  = PVCCMCP_CPU0
  CV25  VSS(350)  GROUND  = GND
  CV27  VSS(349)  GROUND  = GND
  CV29  DDR5_DQS_DP(16)  BI  = M_F_DQS_DP<16>
  CV31  VSS(348)  GROUND  = GND
  CV33  VSS(347)  GROUND  = GND
  CV35  DDR5_DQS_DP(15)  BI  = M_F_DQS_DP<15>
  CV37  VSS(346)  GROUND  = GND
  CV39  VSS(345)  GROUND  = GND
  CV41  VSS(344)  GROUND  = GND
  CV51  VCCIN(5)  POWER  = PVCCIN_CPU0
  CV53  VSS(343)  GROUND  = GND
  CV55  VSS(342)  GROUND  = GND
  CV57  PIROM_ADDR(1)  BI  = PD_PIROM_CPU0_ADDR1
  CV59  SM_WP  IN  = FM_CPU0_SM_WP
  CV61  DDR5_CAVREF  OUT  = M_F_CPU_VREF
  CV63  VSS(341)  GROUND  = GND
  CV65  DDR5_DQS_DN(3)  BI  = M_F_DQS_DN<3>
  CV67  VSS(340)  GROUND  = GND
  CV69  RSVD(64)  BI  = TP_CPU0_RSVD_64
  CV73  VSS(339)  GROUND  = GND
  CV75  DDR5_DQ(6)  BI  = M_F_DQ<6>
  CV77  DDR5_DQ(3)  BI  = M_F_DQ<3>
  CV79  VSS(338)  GROUND  = GND
  CV81  VSS(337)  GROUND  = GND
  CV83  VSS(336)  GROUND  = GND
  CV85  DDR3_DQS_DP(0)  BI  = M_D_DQS_DP<0>
  CW2  PE1_TX_DP(0)  OUT  = P3E_CPU0_PE1_SS_TXP<0>
  CW4  PE2_TX_DP(0)  OUT  = P3E_CPU0_PE2_SS_TXP<0>
  CW6  VSS(1192)  GROUND  = GND
  CW8  PE1_RX_DN(0)  IN  = P3E_CPU0_PE1_SS_RXN<0>
  CW10  PE3_RX_DP(14)  IN  = P3E_CPU0_PE3_OCP_RXP<14>
  CW12  VSS(335)  GROUND  = GND
  CW14  UPI2_TX_DN(11)  OUT  = TP_CPU0_UPI2_RSVD_DF15
  CW16  UPI2_TX_DP(10)  OUT  = TP_CPU0_UPI2_RSVD_DB15
  CW18  UPI2_RX_DP(7)  IN  = GND
  CW20  UPI2_RX_DN(6)  IN  = GND
  CW22  RSVD(63)  BI  = TP_CPU0_KTI2_DFX_DN
  CW24  RSVD(62)  BI  = PVCCMCP_CPU0
  CW26  VSS(334)  GROUND  = GND
  CW28  DDR5_DQ(62)  BI  = M_F_DQ<62>
  CW30  DDR5_DQ(56)  BI  = M_F_DQ<56>
  CW32  VSS(333)  GROUND  = GND
  CW34  DDR5_DQ(54)  BI  = M_F_DQ<54>
  CW36  DDR5_DQ(48)  BI  = M_F_DQ<48>
  CW38  VSS(332)  GROUND  = GND
  CW40  VSS(331)  GROUND  = GND
  CW42  VSS(330)  GROUND  = GND
  CW46  VCCIN(4)  POWER  = PVCCIN_CPU0
  CW48  VCCIN(3)  POWER  = PVCCIN_CPU0
  CW50  VCCIN(2)  POWER  = PVCCIN_CPU0
  CW52  VSS(329)  GROUND  = GND
  CW54  VSS(328)  GROUND  = GND
  CW56  PIROM_ADDR(2)  BI  = PD_PIROM_CPU0_ADDR2
  CW58  SMBDAT  BI  = SMB_PIROM_CPU0_SDA
  CW60  RSVD(61)  BI  = TP_CPU0_RSVD_61
  CW62  RSVD(60)  BI  = TP_CPU0_RSVD_60
  CW64  VSS(327)  GROUND  = GND
  CW66  VSS(326)  GROUND  = GND
  CW68  VSS(325)  GROUND  = GND
  CW72  PKGID(1)  BI  = FM_CPU0_PKGID1
  CW74  VSS(324)  GROUND  = GND
  CW76  DDR5_DQ(2)  BI  = M_F_DQ<2>
  CW78  VSS(323)  GROUND  = GND
  CW80  DDR4_DQ(13)  BI  = M_E_DQ<13>
  CW82  VSS(322)  GROUND  = GND
  CW84  DDR3_DQ(7)  BI  = M_D_DQ<7>
  CW86  DDR3_DQ(6)  BI  = M_D_DQ<6>
  CY1  VSS(321)  GROUND  = GND
  CY3  PE2_TX_DN(0)  OUT  = P3E_CPU0_PE2_SS_TXN<0>
  CY5  PE3_TX_DN(15)  OUT  = P3E_CPU0_PE3_OCP_TXN<15>
  CY7  PE1_RX_DP(1)  IN  = P3E_CPU0_PE1_SS_RXP<1>
  CY9  VSS(320)  GROUND  = GND
  CY11  PE3_RX_DN(14)  IN  = P3E_CPU0_PE3_OCP_RXN<14>
  CY13  VSS(319)  GROUND  = GND
  CY15  VSS(318)  GROUND  = GND
  CY17  VCCIO(15)  POWER  = PVCCIO_CPU0
  CY19  UPI2_RX_DP(5)  IN  = GND
  CY21  VSS(317)  GROUND  = GND
  CY23  RSVD(59)  BI  = TP_CPU0_RSVD_59
  CY25  RSVD(58)  BI  = PVCCMCP_CPU0
  CY27  DDR5_DQ(58)  BI  = M_F_DQ<58>
  CY29  DDR5_DQS_DN(16)  BI  = M_F_DQS_DN<16>
  CY31  DDR5_DQ(60)  BI  = M_F_DQ<60>
  CY33  DDR5_DQ(50)  BI  = M_F_DQ<50>
  CY35  DDR5_DQS_DN(15)  BI  = M_F_DQS_DN<15>
  CY37  DDR5_DQ(52)  BI  = M_F_DQ<52>
  CY39  RSVD(57)  BI  = TP_CPU0_RSVD_57
  CY41  VSS(316)  GROUND  = GND
  CY45  VSS(315)  GROUND  = GND
  CY47  VCCIN(1)  POWER  = PVCCIN_CPU0
  CY49  VCCIN(0)  POWER  = PVCCIN_CPU0
  CY51  VSS(314)  GROUND  = GND
  CY53  RSVD(56)  BI  = TP_CPU0_RSVD_56
  CY55  VCC33  POWER  = P3V3_STBY
  CY57  RSVD(55)  BI  = TP_CPU0_RSVD_55
  CY59  VSS(313)  GROUND  = GND
  CY61  VSS(312)  GROUND  = GND
  CY63  RSVD(54)  BI  = TP_CPU0_RSVD_54
  CY65  VSS(311)  GROUND  = GND
  CY67  DDR3_DQS_DP(17)  BI  = M_D_DQS_DP<17>
  CY69  VSS(310)  GROUND  = GND
  CY71  PROC_ID(0)  OUT  = FM_CPU0_PROC_ID0
  CY73  RSVD(53)  BI  = TP_CPU0_RSVD_53
  CY75  VSS(309)  GROUND  = GND
  CY77  VSS(308)  GROUND  = GND
  CY79  DDR4_DQ(12)  BI  = M_E_DQ<12>
  CY81  DDR4_DQ(9)  BI  = M_E_DQ<9>
  CY83  VSS(307)  GROUND  = GND
  CY85  VSS(306)  GROUND  = GND
  D3  VSS(1246)  GROUND  = GND
  D5  RSVD(287)  BI  = TP_CPU0_RSVD_287
  D7  VCCIO(25)  POWER  = PVCCIO_CPU0
  D9  UPI1_TX_DN(7)  OUT  = UPI_CPU0_CPU1_P1P1_DN<12>
  D11  VSS(1167)  GROUND  = GND
  D13  VSS(1166)  GROUND  = GND
  D15  UPI1_TX_DN(12)  OUT  = UPI_CPU0_CPU1_P1P1_DN<7>
  D17  RSVD(286)  BI  = TP_CPU0_RSVD_286
  D25  VSS(1165)  GROUND  = GND
  D27  VSS(1164)  GROUND  = GND
  D29  VSS(1163)  GROUND  = GND
  D31  VSS(1162)  GROUND  = GND
  D33  VSS(1161)  GROUND  = GND
  D35  VSS(1160)  GROUND  = GND
  D37  VSS(1159)  GROUND  = GND
  D39  VSS(1158)  GROUND  = GND
  D41  VSS(1157)  GROUND  = GND
  D43  VSS(1156)  GROUND  = GND
  D45  VCCD012(49)  POWER  = PVDDQ_ABC
  D47  DDR0_CS_N(2)  OUT  = M_A_CS_N<2>
  D49  DDR0_CS_N(5)  OUT  = M_A_CS_N<5>
  D51  DDR0_MA(16)  OUT  = M_A_MA<16>
  D53  DDR0_PAR  OUT  = M_A_PAR
  D55  DDR0_CLK_DP(0)  OUT  = M_A_CLK_DP<0>
  D57  DDR0_MA(2)  OUT  = M_A_MA<2>
  D59  DDR0_MA(6)  OUT  = M_A_MA<6>
  D61  DDR0_BG(0)  OUT  = M_A_BG<0>
  D63  DDR0_CKE(3)  OUT  = M_A_CKE<3>
  D65  RSVD(285)  BI  = TP_CPU0_RSVD_285
  D71  DDR1_DQ(26)  BI  = M_B_DQ<26>
  D73  DDR1_DQS_DP(12)  BI  = M_B_DQS_DP<12>
  D75  DDR1_DQ(24)  BI  = M_B_DQ<24>
  D77  VSS(1155)  GROUND  = GND
  D79  DDR1_DQS_DN(11)  BI  = M_B_DQS_DN<11>
  D81  VSS(1245)  GROUND  = GND
  D83  RSVD(284)  BI  = TP_CPU0_RSVD_284
  DA2  PE1_TX_DN(0)  OUT  = P3E_CPU0_PE1_SS_TXN<0>
  DA4  PE3_TX_DP(14)  OUT  = P3E_CPU0_PE3_OCP_TXP<14>
  DA6  VSS(305)  GROUND  = GND
  DA8  PE1_RX_DN(1)  IN  = P3E_CPU0_PE1_SS_RXN<1>
  DA10  PE1_RX_DP(3)  IN  = P3E_CPU0_PE1_SS_RXP<3>
  DA12  PE3_RX_DP(13)  IN  = P3E_CPU0_PE3_OCP_RXP<13>
  DA14  VCCIO(33)  POWER  = PVCCIO_CPU0
  DA16  UPI2_TX_DN(10)  OUT  = TP_CPU0_UPI2_RSVD_DC16
  DA18  VSS(303)  GROUND  = GND
  DA20  UPI2_RX_DN(5)  IN  = GND
  DA22  UPI2_RX_DP(2)  IN  = GND
  DA24  RSVD(52)  BI  = PVCCMCP_CPU0
  DA26  VSS(302)  GROUND  = GND
  DA28  VSS(301)  GROUND  = GND
  DA30  VSS(300)  GROUND  = GND
  DA32  VSS(299)  GROUND  = GND
  DA34  VSS(298)  GROUND  = GND
  DA36  VSS(297)  GROUND  = GND
  DA38  VSS(296)  GROUND  = GND
  DA40  RSVD(51)  BI  = TP_CPU0_RSVD_51
  DA42  DDR5_DQ(36)  BI  = M_F_DQ<36>
  DA44  VSS(295)  GROUND  = GND
  DA46  VSS(294)  GROUND  = GND
  DA48  VSS(293)  GROUND  = GND
  DA50  VSS(292)  GROUND  = GND
  DA52  RSVD(50)  BI  = TP_CPU0_RSVD_50
  DA54  RSVD(49)  BI  = TP_CPU0_RSVD_49
  DA56  RSVD(48)  BI  = TP_CPU0_RSVD_48
  DA58  DDR5_MA(9)  OUT  = M_F_MA<9>
  DA60  DDR5_MA(11)  OUT  = M_F_MA<11>
  DA62  DDR5_BG(0)  OUT  = M_F_BG<0>
  DA64  VSS(291)  GROUND  = GND
  DA66  DDR3_ECC(6)  BI  = M_D_ECC<6>
  DA68  DDR3_ECC(0)  BI  = M_D_ECC<0>
  DA70  VSS(290)  GROUND  = GND
  DA72  PKGID(2)  BI  = FM_CPU0_PKGID2
  DA74  VSS(289)  GROUND  = GND
  DA76  VSS(288)  GROUND  = GND
  DA78  VSS(287)  GROUND  = GND
  DA80  VSS(286)  GROUND  = GND
  DA82  DDR4_DQS_DN(1)  BI  = M_E_DQS_DN<1>
  DA84  DDR3_DQ(3)  BI  = M_D_DQ<3>
  DA86  DDR3_DQ(2)  BI  = M_D_DQ<2>
  DB1  PE1_TX_DP(1)  OUT  = P3E_CPU0_PE1_SS_TXP<1>
  DB3  VSS(285)  GROUND  = GND
  DB5  PE3_TX_DN(14)  OUT  = P3E_CPU0_PE3_OCP_TXN<14>
  DB7  VSS(1086)  GROUND  = GND
  DB9  PE1_RX_DP(2)  IN  = P3E_CPU0_PE1_SS_RXP<2>
  DB11  PE3_RX_DN(13)  IN  = P3E_CPU0_PE3_OCP_RXN<13>
  DB13  VSS(284)  GROUND  = GND
  DB15  UPI2_TX_DP(9)  OUT  = TP_CPU0_UPI2_RSVD_CW16
  DB17  VSS(283)  GROUND  = GND
  DB19  UPI2_RX_DP(4)  IN  = GND
  DB21  UPI2_RX_DN(3)  IN  = GND
  DB23  VSS(282)  GROUND  = GND
  DB25  VSS(281)  GROUND  = GND
  DB27  DDR5_DQ(59)  BI  = M_F_DQ<59>
  DB29  DDR5_DQS_DP(7)  BI  = M_F_DQS_DP<7>
  DB31  DDR5_DQ(61)  BI  = M_F_DQ<61>
  DB33  DDR5_DQ(51)  BI  = M_F_DQ<51>
  DB35  DDR5_DQS_DP(6)  BI  = M_F_DQS_DP<6>
  DB37  DDR5_DQ(53)  BI  = M_F_DQ<53>
  DB39  VSS(280)  GROUND  = GND
  DB41  VSS(279)  GROUND  = GND
  DB45  SVIDDATA(0)  BI  = SVID_DIO0_CPU0
  DB47  VSS(278)  GROUND  = GND
  DB49  VSS(277)  GROUND  = GND
  DB51  TEST_13  BI  = PD_CPU0_TEST13
  DB53  VCCD345(48)  POWER  = PVDDQ_DEF
  DB55  VCCD345(47)  POWER  = PVDDQ_DEF
  DB57  VCCD345(46)  POWER  = PVDDQ_DEF
  DB59  VCCD345(45)  POWER  = PVDDQ_DEF
  DB61  VCCD345(44)  POWER  = PVDDQ_DEF
  DB63  VCCD345(43)  POWER  = PVDDQ_DEF
  DB65  DDR3_ECC(2)  BI  = M_D_ECC<2>
  DB67  DDR3_DQS_DN(17)  BI  = M_D_DQS_DN<17>
  DB69  DDR3_ECC(4)  BI  = M_D_ECC<4>
  DB71  PROC_ID(1)  OUT  = FM_CPU0_PROC_ID1
  DB73  VSS(276)  GROUND  = GND
  DB75  DDR5_DQ(13)  BI  = M_F_DQ<13>
  DB77  VSS(275)  GROUND  = GND
  DB79  DDR4_DQ(8)  BI  = M_E_DQ<8>
  DB81  DDR4_DQS_DP(1)  BI  = M_E_DQS_DP<1>
  DB83  VSS(274)  GROUND  = GND
  DB85  VSS(273)  GROUND  = GND
  DC2  PE1_TX_DN(1)  OUT  = P3E_CPU0_PE1_SS_TXN<1>
  DC4  PE1_TX_DP(3)  OUT  = P3E_CPU0_PE1_SS_TXP<3>
  DC6  PE3_TX_DP(13)  OUT  = P3E_CPU0_PE3_OCP_TXP<13>
  DC8  PE1_RX_DN(2)  IN  = P3E_CPU0_PE1_SS_RXN<2>
  DC10  PE1_RX_DN(3)  IN  = P3E_CPU0_PE1_SS_RXN<3>
  DC12  PE3_RX_DP(12)  IN  = P3E_CPU0_PE3_OCP_RXP<12>
  DC14  VSS(272)  GROUND  = GND
  DC16  UPI2_TX_DN(9)  OUT  = TP_CPU0_UPI2_RSVD_DA16
  DC18  VCCIO(14)  POWER  = PVCCIO_CPU0
